# S9S_MB_2U (Grand Teton) — schematic netlist excerpt (pin names and nets, part order shuffled) for the footprints in the layout excerpt that follows; sources: Cadence DE-HDL packaged netlist, KiCad conversion of 03242023_DA0F0TMBIJ0_F0T_Motherboard_J_brd_V01_OCP.brd

R4518  Q_RES  10K 1% CHIP  pkg 0402LF  page 211 : A = P3V3 ; B = CLK_GPU_2_OE_N
PC2282  Q_CAP  0.01UF 25V 10% X7R  pkg 0402  page 299 : A = SH_PVPP_HBM_CPU1_P ; B = SH_PVPP_HBM_CPU1_N

(kicad_pcb
	(version 20260206)
	(generator "pcbnew")
	(generator_version "10.0")
	(general
		(thickness 1.6)
		(legacy_teardrops no)
	)
	(paper "A4")
	(title_block
		(title "03242023_DA0F0TMBIJ0_F0T_Motherboard_J_brd_V01_OCP.brd")
		(comment 1 "Grand Teton / footprints 4497-4498 of 6105")
	)
	(layers
		(0 "F.Cu" signal "TOP")
		(4 "In1.Cu" signal "GND")
		(6 "In2.Cu" signal "IN1")
		(8 "In3.Cu" signal "GND1")
		(10 "In4.Cu" signal "IN2")
		(12 "In5.Cu" signal "GND2")
		(14 "In6.Cu" signal "IN3")
		(16 "In7.Cu" signal "GND3")
		(18 "In8.Cu" signal "VCC")
		(20 "In9.Cu" signal "VCC1")
		(22 "In10.Cu" signal "GND4")
		(24 "In11.Cu" signal "IN4")
		(26 "In12.Cu" signal "GND5")
		(28 "In13.Cu" signal "IN5")
		(30 "In14.Cu" signal "GND6")
		(32 "In15.Cu" signal "IN6")
		(34 "In16.Cu" signal "GND7")
		(2 "B.Cu" signal "BOTTOM")
		(9 "F.Adhes" user "F.Adhesive")
		(11 "B.Adhes" user "B.Adhesive")
		(13 "F.Paste" user "Package Geometry/Pastemask Top")
		(15 "B.Paste" user "Package Geometry/Pastemask Bottom")
		(5 "F.SilkS" user "Ref Des/Silkscreen Top")
		(7 "B.SilkS" user "Ref Des/Silkscreen Bottom")
		(1 "F.Mask" user "Board Geometry/Soldermask Top")
		(3 "B.Mask" user "Board Geometry/Soldermask Bottom")
		(17 "Dwgs.User" user "User.Drawings")
		(19 "Cmts.User" user "User.Comments")
		(21 "Eco1.User" user "User.Eco1")
		(23 "Eco2.User" user "User.Eco2")
		(25 "Edge.Cuts" user "Board Geometry/Outline")
		(27 "Margin" user)
		(31 "F.CrtYd" user "Package Geometry/Place Bound Top")
		(29 "B.CrtYd" user "Package Geometry/Place Bound Bottom")
		(35 "F.Fab" user "Ref Des/Assembly Top")
		(33 "B.Fab" user "Ref Des/Assembly Bottom")
	)
	(footprint ""
		(layer "B.Cu")
		(at 193.384678 -126.405132 180)
		(property "Reference" "R4518"
			(at 0 0 0)
			(layer "B.SilkS")
			(hide yes)
			(effects
				(font
					(size 1.27 1.27)
				)
				(justify mirror)
			)
		)
		(property "Value" ""
			(at 0 0 0)
			(layer "B.Fab")
			(effects
				(font
					(size 1.27 1.27)
				)
				(justify mirror)
			)
		)
		(duplicate_pad_numbers_are_jumpers no)
		(fp_line
			(start 0.7874 0.4064)
			(end 0.7874 -0.4064)
			(stroke
				(width 0.1524)
				(type default)
			)
			(layer "B.SilkS")
		)
		(fp_line
			(start 0.7874 -0.4064)
			(end -0.7874 -0.4064)
			(stroke
				(width 0.1524)
				(type default)
			)
			(layer "B.SilkS")
		)
		(fp_line
			(start -0.7874 0.4064)
			(end 0.7874 0.4064)
			(stroke
				(width 0.1524)
				(type default)
			)
			(layer "B.SilkS")
		)
		(fp_line
			(start -0.7874 -0.4064)
			(end -0.7874 0.4064)
			(stroke
				(width 0.1524)
				(type default)
			)
			(layer "B.SilkS")
		)
		(fp_line
			(start 0.67945 0.3048)
			(end 0.67945 -0.305054)
			(stroke
				(width 0.1)
				(type default)
			)
			(layer "B.Fab")
		)
		(fp_line
			(start 0.67945 -0.305054)
			(end 0.12065 -0.305054)
			(stroke
				(width 0.1)
				(type default)
			)
			(layer "B.Fab")
		)
		(fp_line
			(start 0.12065 0.3048)
			(end 0.67945 0.3048)
			(stroke
				(width 0.1)
				(type default)
			)
			(layer "B.Fab")
		)
		(fp_line
			(start 0.12065 0.2794)
			(end 0.12065 0.3048)
			(stroke
				(width 0.1)
				(type default)
			)
			(layer "B.Fab")
		)
		(fp_line
			(start 0.12065 -0.2794)
			(end -0.12065 -0.2794)
			(stroke
				(width 0.1)
				(type default)
			)
			(layer "B.Fab")
		)
		(fp_line
			(start 0.12065 -0.305054)
			(end 0.12065 -0.2794)
			(stroke
				(width 0.1)
				(type default)
			)
			(layer "B.Fab")
		)
		(fp_line
			(start -0.120396 0.3048)
			(end -0.120396 0.2794)
			(stroke
				(width 0.1)
				(type default)
			)
			(layer "B.Fab")
		)
		(fp_line
			(start -0.120396 0.2794)
			(end 0.12065 0.2794)
			(stroke
				(width 0.1)
				(type default)
			)
			(layer "B.Fab")
		)
		(fp_line
			(start -0.12065 -0.2794)
			(end -0.12065 -0.3048)
			(stroke
				(width 0.1)
				(type default)
			)
			(layer "B.Fab")
		)
		(fp_line
			(start -0.12065 -0.3048)
			(end -0.67945 -0.3048)
			(stroke
				(width 0.1)
				(type default)
			)
			(layer "B.Fab")
		)
		(fp_line
			(start -0.67945 0.3048)
			(end -0.120396 0.3048)
			(stroke
				(width 0.1)
				(type default)
			)
			(layer "B.Fab")
		)
		(fp_line
			(start -0.67945 -0.3048)
			(end -0.67945 0.3048)
			(stroke
				(width 0.1)
				(type default)
			)
			(layer "B.Fab")
		)
		(pad "1" smd circle
			(at 0.40005 0)
			(size 0 0)
			(layers "B.Cu" "B.Mask" "B.Paste")
			(net "P3V3")
		)
		(pad "2" smd circle
			(at -0.40005 0)
			(size 0 0)
			(layers "B.Cu" "B.Mask" "B.Paste")
			(net "CLK_GPU_2_OE_N")
		)
	)
	(footprint ""
		(layer "B.Cu")
		(at 121.1326 -357.675688 180)
		(property "Reference" "PC2282"
			(at 0 0 0)
			(layer "B.SilkS")
			(hide yes)
			(effects
				(font
					(size 1.27 1.27)
				)
				(justify mirror)
			)
		)
		(property "Value" ""
			(at 0 0 0)
			(layer "B.Fab")
			(effects
				(font
					(size 1.27 1.27)
				)
				(justify mirror)
			)
		)
		(duplicate_pad_numbers_are_jumpers no)
		(fp_line
			(start 0.7874 0.4064)
			(end 0.7874 -0.4064)
			(stroke
				(width 0.1524)
				(type default)
			)
			(layer "B.SilkS")
		)
		(fp_line
			(start 0.7874 -0.4064)
			(end -0.7874 -0.4064)
			(stroke
				(width 0.1524)
				(type default)
			)
			(layer "B.SilkS")
		)
		(fp_line
			(start -0.7874 0.4064)
			(end 0.7874 0.4064)
			(stroke
				(width 0.1524)
				(type default)
			)
			(layer "B.SilkS")
		)
		(fp_line
			(start -0.7874 -0.4064)
			(end -0.7874 0.4064)
			(stroke
				(width 0.1524)
				(type default)
			)
			(layer "B.SilkS")
		)
		(fp_line
			(start 0.67945 0.3048)
			(end 0.67945 -0.305054)
			(stroke
				(width 0.1)
				(type default)
			)
			(layer "B.Fab")
		)
		(fp_line
			(start 0.67945 -0.305054)
			(end 0.12065 -0.305054)
			(stroke
				(width 0.1)
				(type default)
			)
			(layer "B.Fab")
		)
		(fp_line
			(start 0.12065 0.3048)
			(end 0.67945 0.3048)
			(stroke
				(width 0.1)
				(type default)
			)
			(layer "B.Fab")
		)
		(fp_line
			(start 0.12065 0.2794)
			(end 0.12065 0.3048)
			(stroke
				(width 0.1)
				(type default)
			)
			(layer "B.Fab")
		)
		(fp_line
			(start 0.12065 -0.2794)
			(end -0.12065 -0.2794)
			(stroke
				(width 0.1)
				(type default)
			)
			(layer "B.Fab")
		)
		(fp_line
			(start 0.12065 -0.305054)
			(end 0.12065 -0.2794)
			(stroke
				(width 0.1)
				(type default)
			)
			(layer "B.Fab")
		)
		(fp_line
			(start -0.120396 0.3048)
			(end -0.120396 0.2794)
			(stroke
				(width 0.1)
				(type default)
			)
			(layer "B.Fab")
		)
		(fp_line
			(start -0.120396 0.2794)
			(end 0.12065 0.2794)
			(stroke
				(width 0.1)
				(type default)
			)
			(layer "B.Fab")
		)
		(fp_line
			(start -0.12065 -0.2794)
			(end -0.12065 -0.3048)
			(stroke
				(width 0.1)
				(type default)
			)
			(layer "B.Fab")
		)
		(fp_line
			(start -0.12065 -0.3048)
			(end -0.67945 -0.3048)
			(stroke
				(width 0.1)
				(type default)
			)
			(layer "B.Fab")
		)
		(fp_line
			(start -0.67945 0.3048)
			(end -0.120396 0.3048)
			(stroke
				(width 0.1)
				(type default)
			)
			(layer "B.Fab")
		)
		(fp_line
			(start -0.67945 -0.3048)
			(end -0.67945 0.3048)
			(stroke
				(width 0.1)
				(type default)
			)
			(layer "B.Fab")
		)
		(pad "1" smd circle
			(at 0.40005 0)
			(size 0 0)
			(layers "B.Cu" "B.Mask" "B.Paste")
			(net "SH_PVPP_HBM_CPU1_P")
		)
		(pad "2" smd circle
			(at -0.40005 0)
			(size 0 0)
			(layers "B.Cu" "B.Mask" "B.Paste")
			(net "SH_PVPP_HBM_CPU1_N")
		)
	)
)
